(kicad_pcb
	(version 20260206)
	(generator "pcbnew")
	(generator_version "10.0")
	(general
		(thickness 1.6)
		(legacy_teardrops no)
	)
	(paper "A4")
	(title_block
		(title "Bryce Canyon_IOM_IOC_16318-2_OCP.brd")
		(comment 1 "Bryce Canyon / footprints 1264-1271 of 1605")
	)
	(layers
		(0 "F.Cu" signal "TOP")
		(4 "In1.Cu" signal "L2GND")
		(6 "In2.Cu" signal "L3")
		(8 "In3.Cu" signal "L4VCC")
		(10 "In4.Cu" signal "L5VCC")
		(12 "In5.Cu" signal "L6")
		(14 "In6.Cu" signal "L7GND")
		(2 "B.Cu" signal "BOTTOM")
		(9 "F.Adhes" user "F.Adhesive")
		(11 "B.Adhes" user "B.Adhesive")
		(13 "F.Paste" user "Package Geometry/Pastemask Top")
		(15 "B.Paste" user "Package Geometry/Pastemask Bottom")
		(5 "F.SilkS" user "Ref Des/Silkscreen Top")
		(7 "B.SilkS" user "Ref Des/Silkscreen Bottom")
		(1 "F.Mask" user "Board Geometry/Soldermask Top")
		(3 "B.Mask" user "Board Geometry/Soldermask Bottom")
		(17 "Dwgs.User" user "User.Drawings")
		(19 "Cmts.User" user "User.Comments")
		(21 "Eco1.User" user "User.Eco1")
		(23 "Eco2.User" user "User.Eco2")
		(25 "Edge.Cuts" user "Board Geometry/Outline")
		(27 "Margin" user)
		(31 "F.CrtYd" user "Package Geometry/Place Bound Top")
		(29 "B.CrtYd" user "Package Geometry/Place Bound Bottom")
		(35 "F.Fab" user "Ref Des/Assembly Top")
		(33 "B.Fab" user "Ref Des/Assembly Bottom")
	)
	(footprint ""
		(layer "B.Cu")
		(at 197.260718 -81.153 180)
		(property "Reference" "C296"
			(at 0 0 0)
			(layer "B.SilkS")
			(hide yes)
			(effects
				(font
					(size 1.27 1.27)
				)
				(justify mirror)
			)
		)
		(property "Value" "SCD22U10V1KX-GP"
			(at 2.8321 -1.7399 180)
			(unlocked yes)
			(layer "B.Fab")
			(hide yes)
			(effects
				(font
					(size 1.016 1.016)
					(thickness 0.1524)
				)
				(justify mirror)
			)
		)
		(property "Device Type" "C0201H13"
			(at 2.8321 -3.2639 180)
			(unlocked yes)
			(layer "B.Fab")
			(hide yes)
			(effects
				(font
					(size 1.016 1.016)
					(thickness 0.1524)
				)
				(justify mirror)
			)
		)
		(duplicate_pad_numbers_are_jumpers no)
		(fp_rect
			(start 0.2794 0.6477)
			(end -0.2794 -0.6477)
			(stroke
				(width 0)
				(type default)
			)
			(fill no)
			(layer "B.CrtYd")
		)
		(fp_rect
			(start 0.2794 0.6477)
			(end -0.2794 -0.6477)
			(stroke
				(width 0)
				(type default)
			)
			(fill no)
			(layer "B.Fab")
		)
		(pad "1" smd custom
			(at 0 -0.2794)
			(size 0.0762 0.0762)
			(layers "B.Cu" "B.Mask" "B.Paste")
			(net "PCIE_IOM_TO_COMP_11_DN_C")
			(options
				(clearance outline)
				(anchor circle)
			)
			(primitives
				(gr_poly
					(pts
						(arc
							(start 0.1524 0.127)
							(mid 0.137521 0.162921)
							(end 0.1016 0.1778)
						)
						(arc
							(start -0.1016 0.1778)
							(mid -0.137521 0.162921)
							(end -0.1524 0.127)
						)
						(arc
							(start -0.1524 -0.127)
							(mid -0.137521 -0.162921)
							(end -0.1016 -0.1778)
						)
						(arc
							(start 0.1016 -0.1778)
							(mid 0.137521 -0.162921)
							(end 0.1524 -0.127)
						)
					)
					(width 0)
					(fill yes)
				)
			)
		)
		(pad "2" smd custom
			(at 0 0.2794)
			(size 0.0762 0.0762)
			(layers "B.Cu" "B.Mask" "B.Paste")
			(net "PCIE_IOM_TO_COMP_11_DN")
			(options
				(clearance outline)
				(anchor circle)
			)
			(primitives
				(gr_poly
					(pts
						(arc
							(start 0.1524 0.127)
							(mid 0.137521 0.162921)
							(end 0.1016 0.1778)
						)
						(arc
							(start -0.1016 0.1778)
							(mid -0.137521 0.162921)
							(end -0.1524 0.127)
						)
						(arc
							(start -0.1524 -0.127)
							(mid -0.137521 -0.162921)
							(end -0.1016 -0.1778)
						)
						(arc
							(start 0.1016 -0.1778)
							(mid 0.137521 -0.162921)
							(end 0.1524 -0.127)
						)
					)
					(width 0)
					(fill yes)
				)
			)
		)
	)
	(footprint ""
		(layer "B.Cu")
		(at 172.593 -77.851 180)
		(property "Reference" "C343"
			(at 0 0 0)
			(layer "B.SilkS")
			(hide yes)
			(effects
				(font
					(size 1.27 1.27)
				)
				(justify mirror)
			)
		)
		(property "Value" "SC10U6D3V5KX-4GP"
			(at 0.0762 -6.1214 180)
			(unlocked yes)
			(layer "B.Fab")
			(hide yes)
			(effects
				(font
					(size 1.016 1.016)
					(thickness 0.1524)
				)
				(justify mirror)
			)
		)
		(property "Device Type" "C805H58"
			(at 0.0762 -8.1534 180)
			(unlocked yes)
			(layer "B.Fab")
			(hide yes)
			(effects
				(font
					(size 1.016 1.016)
					(thickness 0.1524)
				)
				(justify mirror)
			)
		)
		(duplicate_pad_numbers_are_jumpers no)
		(fp_line
			(start -0.635 0)
			(end 0.635 0)
			(stroke
				(width 0.508)
				(type default)
			)
			(layer "B.SilkS")
		)
		(fp_rect
			(start 0.9652 1.778)
			(end -0.9652 -1.778)
			(stroke
				(width 0)
				(type default)
			)
			(fill no)
			(layer "B.CrtYd")
		)
		(fp_poly
			(pts
				(xy 0.9652 -1.778) (xy -0.9652 -1.778) (xy -0.9652 1.778) (xy 0.9652 1.778)
			)
			(stroke
				(width 0)
				(type default)
			)
			(fill no)
			(layer "B.Fab")
		)
		(pad "1" smd rect
			(at 0 -0.9652)
			(size 1.397 1.143)
			(layers "B.Cu" "B.Mask" "B.Paste")
			(net "PLL_VDD")
		)
		(pad "2" smd rect
			(at 0 0.9652)
			(size 1.397 1.143)
			(layers "B.Cu" "B.Mask" "B.Paste")
			(net "GND")
		)
	)
	(footprint ""
		(layer "B.Cu")
		(at 41.3512 -125.1204 180)
		(property "Reference" "R362"
			(at 0 0 0)
			(layer "B.SilkS")
			(hide yes)
			(effects
				(font
					(size 1.27 1.27)
				)
				(justify mirror)
			)
		)
		(property "Value" "4K7R2F-GP"
			(at -0.064008 -3.993896 180)
			(unlocked yes)
			(layer "B.Fab")
			(hide yes)
			(effects
				(font
					(size 1.016 1.016)
					(thickness 0.1524)
				)
				(justify mirror)
			)
		)
		(property "Device Type" "R402H16"
			(at -0.064008 -5.517896 180)
			(unlocked yes)
			(layer "B.Fab")
			(hide yes)
			(effects
				(font
					(size 1.016 1.016)
					(thickness 0.1524)
				)
				(justify mirror)
			)
		)
		(duplicate_pad_numbers_are_jumpers no)
		(fp_line
			(start 0.508 -0.9398)
			(end 0.508 0.9398)
			(stroke
				(width 0.1524)
				(type default)
			)
			(layer "B.SilkS")
		)
		(fp_line
			(start -0.508 -0.9398)
			(end 0.508 -0.9398)
			(stroke
				(width 0.1524)
				(type default)
			)
			(layer "B.SilkS")
		)
		(fp_rect
			(start 0.508 0.9398)
			(end -0.508 -0.9398)
			(stroke
				(width 0)
				(type default)
			)
			(fill no)
			(layer "B.CrtYd")
		)
		(fp_rect
			(start 0.508 0.9398)
			(end -0.508 -0.9398)
			(stroke
				(width 0)
				(type default)
			)
			(fill no)
			(layer "B.Fab")
		)
		(pad "1" smd custom
			(at 0 -0.4445)
			(size 0.1397 0.1397)
			(layers "B.Cu" "B.Mask" "B.Paste")
			(net "P3V3_STBY")
			(options
				(clearance outline)
				(anchor circle)
			)
			(primitives
				(gr_poly
					(pts
						(arc
							(start -0.1778 0.2794)
							(mid -0.249642 0.249642)
							(end -0.2794 0.1778)
						)
						(arc
							(start -0.2794 -0.1778)
							(mid -0.249642 -0.249642)
							(end -0.1778 -0.2794)
						)
						(arc
							(start 0.1778 -0.2794)
							(mid 0.249642 -0.249642)
							(end 0.2794 -0.1778)
						)
						(arc
							(start 0.2794 0.1778)
							(mid 0.249642 0.249642)
							(end 0.1778 0.2794)
						)
					)
					(width 0)
					(fill yes)
				)
			)
		)
		(pad "2" smd custom
			(at 0 0.4445)
			(size 0.1397 0.1397)
			(layers "B.Cu" "B.Mask" "B.Paste")
			(net "FM_BMC_RESET_N")
			(options
				(clearance outline)
				(anchor circle)
			)
			(primitives
				(gr_poly
					(pts
						(arc
							(start -0.1778 0.2794)
							(mid -0.249642 0.249642)
							(end -0.2794 0.1778)
						)
						(arc
							(start -0.2794 -0.1778)
							(mid -0.249642 -0.249642)
							(end -0.1778 -0.2794)
						)
						(arc
							(start 0.1778 -0.2794)
							(mid 0.249642 -0.249642)
							(end 0.2794 -0.1778)
						)
						(arc
							(start 0.2794 0.1778)
							(mid 0.249642 0.249642)
							(end 0.1778 0.2794)
						)
					)
					(width 0)
					(fill yes)
				)
			)
		)
	)
	(footprint ""
		(layer "B.Cu")
		(at 199.31126 -63.46952 90)
		(property "Reference" "R648"
			(at 0 0 90)
			(layer "B.SilkS")
			(hide yes)
			(effects
				(font
					(size 1.27 1.27)
				)
				(justify mirror)
			)
		)
		(property "Value" "10KR2F-2-GP"
			(at -0.064008 -3.993896 90)
			(unlocked yes)
			(layer "B.Fab")
			(hide yes)
			(effects
				(font
					(size 1.016 1.016)
					(thickness 0.1524)
				)
				(justify mirror)
			)
		)
		(property "Device Type" "R402H16"
			(at -0.064008 -5.517896 90)
			(unlocked yes)
			(layer "B.Fab")
			(hide yes)
			(effects
				(font
					(size 1.016 1.016)
					(thickness 0.1524)
				)
				(justify mirror)
			)
		)
		(duplicate_pad_numbers_are_jumpers no)
		(fp_line
			(start 0.508 -0.9398)
			(end 0.508 0.9398)
			(stroke
				(width 0.1524)
				(type default)
			)
			(layer "B.SilkS")
		)
		(fp_line
			(start -0.508 -0.9398)
			(end 0.508 -0.9398)
			(stroke
				(width 0.1524)
				(type default)
			)
			(layer "B.SilkS")
		)
		(fp_rect
			(start 0.508 0.9398)
			(end -0.508 -0.9398)
			(stroke
				(width 0)
				(type default)
			)
			(fill no)
			(layer "B.CrtYd")
		)
		(fp_rect
			(start 0.508 0.9398)
			(end -0.508 -0.9398)
			(stroke
				(width 0)
				(type default)
			)
			(fill no)
			(layer "B.Fab")
		)
		(pad "1" smd custom
			(at 0 -0.4445 270)
			(size 0.1397 0.1397)
			(layers "B.Cu" "B.Mask" "B.Paste")
			(net "P1V8")
			(options
				(clearance outline)
				(anchor circle)
			)
			(primitives
				(gr_poly
					(pts
						(arc
							(start -0.1778 0.2794)
							(mid -0.249642 0.249642)
							(end -0.2794 0.1778)
						)
						(arc
							(start -0.2794 -0.1778)
							(mid -0.249642 -0.249642)
							(end -0.1778 -0.2794)
						)
						(arc
							(start 0.1778 -0.2794)
							(mid 0.249642 -0.249642)
							(end 0.2794 -0.1778)
						)
						(arc
							(start 0.2794 0.1778)
							(mid 0.249642 0.249642)
							(end 0.1778 0.2794)
						)
					)
					(width 0)
					(fill yes)
				)
			)
		)
		(pad "2" smd custom
			(at 0 0.4445 270)
			(size 0.1397 0.1397)
			(layers "B.Cu" "B.Mask" "B.Paste")
			(net "POWERLOSS#")
			(options
				(clearance outline)
				(anchor circle)
			)
			(primitives
				(gr_poly
					(pts
						(arc
							(start -0.1778 0.2794)
							(mid -0.249642 0.249642)
							(end -0.2794 0.1778)
						)
						(arc
							(start -0.2794 -0.1778)
							(mid -0.249642 -0.249642)
							(end -0.1778 -0.2794)
						)
						(arc
							(start 0.1778 -0.2794)
							(mid 0.249642 -0.249642)
							(end 0.2794 -0.1778)
						)
						(arc
							(start 0.2794 0.1778)
							(mid 0.249642 0.249642)
							(end 0.1778 0.2794)
						)
					)
					(width 0)
					(fill yes)
				)
			)
		)
	)
	(footprint ""
		(layer "B.Cu")
		(at 33.9344 -150.8252 180)
		(property "Reference" "C93"
			(at 0 0 0)
			(layer "B.SilkS")
			(hide yes)
			(effects
				(font
					(size 1.27 1.27)
				)
				(justify mirror)
			)
		)
		(property "Value" "SCD1U16V2KX-3GP"
			(at -1.1811 -2.7051 180)
			(unlocked yes)
			(layer "B.Fab")
			(hide yes)
			(effects
				(font
					(size 1.016 1.016)
					(thickness 0.1524)
				)
				(justify mirror)
			)
		)
		(property "Device Type" "C402H22"
			(at -1.1811 -4.2291 180)
			(unlocked yes)
			(layer "B.Fab")
			(hide yes)
			(effects
				(font
					(size 1.016 1.016)
					(thickness 0.1524)
				)
				(justify mirror)
			)
		)
		(duplicate_pad_numbers_are_jumpers no)
		(fp_rect
			(start 0.4318 0.9525)
			(end -0.4318 -0.9525)
			(stroke
				(width 0)
				(type default)
			)
			(fill no)
			(layer "B.CrtYd")
		)
		(fp_rect
			(start 0.4318 0.9525)
			(end -0.4318 -0.9525)
			(stroke
				(width 0)
				(type default)
			)
			(fill no)
			(layer "B.Fab")
		)
		(pad "1" smd custom
			(at 0 -0.4445)
			(size 0.1524 0.1524)
			(layers "B.Cu" "B.Mask" "B.Paste")
			(net "MPLLAV33")
			(options
				(clearance outline)
				(anchor circle)
			)
			(primitives
				(gr_poly
					(pts
						(arc
							(start 0.3048 0.2032)
							(mid 0.275042 0.275042)
							(end 0.2032 0.3048)
						)
						(arc
							(start -0.2032 0.3048)
							(mid -0.275042 0.275042)
							(end -0.3048 0.2032)
						)
						(arc
							(start -0.3048 -0.2032)
							(mid -0.275042 -0.275042)
							(end -0.2032 -0.3048)
						)
						(arc
							(start 0.2032 -0.3048)
							(mid 0.275042 -0.275042)
							(end 0.3048 -0.2032)
						)
					)
					(width 0)
					(fill yes)
				)
			)
		)
		(pad "2" smd custom
			(at 0 0.4445)
			(size 0.1524 0.1524)
			(layers "B.Cu" "B.Mask" "B.Paste")
			(net "GND")
			(options
				(clearance outline)
				(anchor circle)
			)
			(primitives
				(gr_poly
					(pts
						(arc
							(start 0.3048 0.2032)
							(mid 0.275042 0.275042)
							(end 0.2032 0.3048)
						)
						(arc
							(start -0.2032 0.3048)
							(mid -0.275042 0.275042)
							(end -0.3048 0.2032)
						)
						(arc
							(start -0.3048 -0.2032)
							(mid -0.275042 -0.275042)
							(end -0.2032 -0.3048)
						)
						(arc
							(start 0.2032 -0.3048)
							(mid 0.275042 -0.275042)
							(end 0.3048 -0.2032)
						)
					)
					(width 0)
					(fill yes)
				)
			)
		)
	)
	(footprint ""
		(layer "B.Cu")
		(at 204.7494 -56.9468 180)
		(property "Reference" "R590"
			(at 0 0 0)
			(layer "B.SilkS")
			(hide yes)
			(effects
				(font
					(size 1.27 1.27)
				)
				(justify mirror)
			)
		)
		(property "Value" "2K2R2F-GP"
			(at -0.064008 -3.993896 180)
			(unlocked yes)
			(layer "B.Fab")
			(hide yes)
			(effects
				(font
					(size 1.016 1.016)
					(thickness 0.1524)
				)
				(justify mirror)
			)
		)
		(property "Device Type" "R402H16"
			(at -0.064008 -5.517896 180)
			(unlocked yes)
			(layer "B.Fab")
			(hide yes)
			(effects
				(font
					(size 1.016 1.016)
					(thickness 0.1524)
				)
				(justify mirror)
			)
		)
		(duplicate_pad_numbers_are_jumpers no)
		(fp_line
			(start 0.508 -0.9398)
			(end 0.508 0.9398)
			(stroke
				(width 0.1524)
				(type default)
			)
			(layer "B.SilkS")
		)
		(fp_line
			(start -0.508 -0.9398)
			(end 0.508 -0.9398)
			(stroke
				(width 0.1524)
				(type default)
			)
			(layer "B.SilkS")
		)
		(fp_rect
			(start 0.508 0.9398)
			(end -0.508 -0.9398)
			(stroke
				(width 0)
				(type default)
			)
			(fill no)
			(layer "B.CrtYd")
		)
		(fp_rect
			(start 0.508 0.9398)
			(end -0.508 -0.9398)
			(stroke
				(width 0)
				(type default)
			)
			(fill no)
			(layer "B.Fab")
		)
		(pad "1" smd custom
			(at 0 -0.4445)
			(size 0.1397 0.1397)
			(layers "B.Cu" "B.Mask" "B.Paste")
			(net "P1V8")
			(options
				(clearance outline)
				(anchor circle)
			)
			(primitives
				(gr_poly
					(pts
						(arc
							(start -0.1778 0.2794)
							(mid -0.249642 0.249642)
							(end -0.2794 0.1778)
						)
						(arc
							(start -0.2794 -0.1778)
							(mid -0.249642 -0.249642)
							(end -0.1778 -0.2794)
						)
						(arc
							(start 0.1778 -0.2794)
							(mid 0.249642 -0.249642)
							(end 0.2794 -0.1778)
						)
						(arc
							(start 0.2794 0.1778)
							(mid 0.249642 0.249642)
							(end 0.1778 0.2794)
						)
					)
					(width 0)
					(fill yes)
				)
			)
		)
		(pad "2" smd custom
			(at 0 0.4445)
			(size 0.1397 0.1397)
			(layers "B.Cu" "B.Mask" "B.Paste")
			(net "SIO_DOUT_0")
			(options
				(clearance outline)
				(anchor circle)
			)
			(primitives
				(gr_poly
					(pts
						(arc
							(start -0.1778 0.2794)
							(mid -0.249642 0.249642)
							(end -0.2794 0.1778)
						)
						(arc
							(start -0.2794 -0.1778)
							(mid -0.249642 -0.249642)
							(end -0.1778 -0.2794)
						)
						(arc
							(start 0.1778 -0.2794)
							(mid 0.249642 -0.249642)
							(end 0.2794 -0.1778)
						)
						(arc
							(start 0.2794 0.1778)
							(mid 0.249642 0.249642)
							(end 0.1778 0.2794)
						)
					)
					(width 0)
					(fill yes)
				)
			)
		)
	)
	(footprint ""
		(layer "B.Cu")
		(at 190.8175 -65.3796 90)
		(property "Reference" "C417"
			(at 0 0 90)
			(layer "B.SilkS")
			(hide yes)
			(effects
				(font
					(size 1.27 1.27)
				)
				(justify mirror)
			)
		)
		(property "Value" "SCD1U6D3V1KX-GP"
			(at 2.8321 -1.7399 90)
			(unlocked yes)
			(layer "B.Fab")
			(hide yes)
			(effects
				(font
					(size 1.016 1.016)
					(thickness 0.1524)
				)
				(justify mirror)
			)
		)
		(property "Device Type" "C0201H13"
			(at 2.8321 -3.2639 90)
			(unlocked yes)
			(layer "B.Fab")
			(hide yes)
			(effects
				(font
					(size 1.016 1.016)
					(thickness 0.1524)
				)
				(justify mirror)
			)
		)
		(duplicate_pad_numbers_are_jumpers no)
		(fp_rect
			(start 0.2794 0.6477)
			(end -0.2794 -0.6477)
			(stroke
				(width 0)
				(type default)
			)
			(fill no)
			(layer "B.CrtYd")
		)
		(fp_rect
			(start 0.2794 0.6477)
			(end -0.2794 -0.6477)
			(stroke
				(width 0)
				(type default)
			)
			(fill no)
			(layer "B.Fab")
		)
		(pad "1" smd custom
			(at 0 -0.2794 270)
			(size 0.0762 0.0762)
			(layers "B.Cu" "B.Mask" "B.Paste")
			(net "P0V975")
			(options
				(clearance outline)
				(anchor circle)
			)
			(primitives
				(gr_poly
					(pts
						(arc
							(start 0.1524 0.127)
							(mid 0.137521 0.162921)
							(end 0.1016 0.1778)
						)
						(arc
							(start -0.1016 0.1778)
							(mid -0.137521 0.162921)
							(end -0.1524 0.127)
						)
						(arc
							(start -0.1524 -0.127)
							(mid -0.137521 -0.162921)
							(end -0.1016 -0.1778)
						)
						(arc
							(start 0.1016 -0.1778)
							(mid 0.137521 -0.162921)
							(end 0.1524 -0.127)
						)
					)
					(width 0)
					(fill yes)
				)
			)
		)
		(pad "2" smd custom
			(at 0 0.2794 270)
			(size 0.0762 0.0762)
			(layers "B.Cu" "B.Mask" "B.Paste")
			(net "GND")
			(options
				(clearance outline)
				(anchor circle)
			)
			(primitives
				(gr_poly
					(pts
						(arc
							(start 0.1524 0.127)
							(mid 0.137521 0.162921)
							(end 0.1016 0.1778)
						)
						(arc
							(start -0.1016 0.1778)
							(mid -0.137521 0.162921)
							(end -0.1524 0.127)
						)
						(arc
							(start -0.1524 -0.127)
							(mid -0.137521 -0.162921)
							(end -0.1016 -0.1778)
						)
						(arc
							(start 0.1016 -0.1778)
							(mid 0.137521 -0.162921)
							(end 0.1524 -0.127)
						)
					)
					(width 0)
					(fill yes)
				)
			)
		)
	)
	(footprint ""
		(layer "B.Cu")
		(at 10.174732 -136.716516 90)
		(property "Reference" "R250"
			(at 0 0 90)
			(layer "B.SilkS")
			(hide yes)
			(effects
				(font
					(size 1.27 1.27)
				)
				(justify mirror)
			)
		)
		(property "Value" "120R2F-GP"
			(at -0.064008 -3.993896 90)
			(unlocked yes)
			(layer "B.Fab")
			(hide yes)
			(effects
				(font
					(size 1.016 1.016)
					(thickness 0.1524)
				)
				(justify mirror)
			)
		)
		(property "Device Type" "R402H16"
			(at -0.064008 -5.517896 90)
			(unlocked yes)
			(layer "B.Fab")
			(hide yes)
			(effects
				(font
					(size 1.016 1.016)
					(thickness 0.1524)
				)
				(justify mirror)
			)
		)
		(duplicate_pad_numbers_are_jumpers no)
		(fp_line
			(start 0.508 -0.9398)
			(end 0.508 0.9398)
			(stroke
				(width 0.1524)
				(type default)
			)
			(layer "B.SilkS")
		)
		(fp_line
			(start -0.508 -0.9398)
			(end 0.508 -0.9398)
			(stroke
				(width 0.1524)
				(type default)
			)
			(layer "B.SilkS")
		)
		(fp_rect
			(start 0.508 0.9398)
			(end -0.508 -0.9398)
			(stroke
				(width 0)
				(type default)
			)
			(fill no)
			(layer "B.CrtYd")
		)
		(fp_rect
			(start 0.508 0.9398)
			(end -0.508 -0.9398)
			(stroke
				(width 0)
				(type default)
			)
			(fill no)
			(layer "B.Fab")
		)
		(pad "1" smd custom
			(at 0 -0.4445 270)
			(size 0.1397 0.1397)
			(layers "B.Cu" "B.Mask" "B.Paste")
			(net "GND")
			(options
				(clearance outline)
				(anchor circle)
			)
			(primitives
				(gr_poly
					(pts
						(arc
							(start -0.1778 0.2794)
							(mid -0.249642 0.249642)
							(end -0.2794 0.1778)
						)
						(arc
							(start -0.2794 -0.1778)
							(mid -0.249642 -0.249642)
							(end -0.1778 -0.2794)
						)
						(arc
							(start 0.1778 -0.2794)
							(mid 0.249642 -0.249642)
							(end 0.2794 -0.1778)
						)
						(arc
							(start 0.2794 0.1778)
							(mid 0.249642 0.249642)
							(end 0.1778 0.2794)
						)
					)
					(width 0)
					(fill yes)
				)
			)
		)
		(pad "2" smd custom
			(at 0 0.4445 270)
			(size 0.1397 0.1397)
			(layers "B.Cu" "B.Mask" "B.Paste")
			(net "MEMA_8")
			(options
				(clearance outline)
				(anchor circle)
			)
			(primitives
				(gr_poly
					(pts
						(arc
							(start -0.1778 0.2794)
							(mid -0.249642 0.249642)
							(end -0.2794 0.1778)
						)
						(arc
							(start -0.2794 -0.1778)
							(mid -0.249642 -0.249642)
							(end -0.1778 -0.2794)
						)
						(arc
							(start 0.1778 -0.2794)
							(mid 0.249642 -0.249642)
							(end 0.2794 -0.1778)
						)
						(arc
							(start 0.2794 0.1778)
							(mid 0.249642 0.249642)
							(end 0.1778 0.2794)
						)
					)
					(width 0)
					(fill yes)
				)
			)
		)
	)
)
